FILE_TYPE = CONNECTIVITY;
{Allegro Design Entry HDL 17.4-2019 S026 (4007227) 1/17/2022}
"PAGE_NUMBER" = 326;
0"NC";
1"FM_SWB_BIC_READY_N";
2"GPU_WP_HW_CTRL_ISO_N";
3"P5E_CPU0_P2_RX_BUF_DN<10>";
4"GND\g";
5"P5E_CPU0_P3_TX_BUF_C_DP<11>";
6"P5E_CPU0_P3_TX_BUF_C_DN<11>";
7"P5E_CPU0_P2_TX_BUF_C_DP<11>";
8"P5E_CPU0_P2_RX_BUF_DP<10>";
9"P5E_CPU0_P3_RX_BUF_DP<10>";
10"P5E_CPU0_P3_TX_BUF_C_DP<8>";
11"P5E_CPU0_P3_TX_BUF_C_DN<8>";
12"P5E_CPU0_P2_TX_BUF_C_DP<8>";
13"P5E_CPU0_P2_TX_BUF_C_DN<8>";
14"P5E_CPU0_P3_RX_BUF_DP<8>";
15"P5E_CPU0_P3_RX_BUF_DN<8>";
16"P5E_CPU0_P2_RX_BUF_DP<8>";
17"P5E_CPU0_P2_RX_BUF_DN<8>";
18"GPU_3V3IO_RSVD4";
19"P5E_CPU0_P3_RX_BUF_DN<9>";
20"P5E_CPU0_P3_RX_BUF_DP<9>";
21"P5E_CPU0_P2_TX_BUF_C_DN<9>";
22"P5E_CPU0_P2_TX_BUF_C_DP<9>";
23"P5E_CPU0_P3_TX_BUF_C_DP<9>";
24"FM_SWB_PWR_EN_R_BUF";
25"P5E_CPU0_P3_TX_BUF_C_DN<9>";
26"P5E_CPU0_P3_TX_BUF_C_DN<10>";
27"P5E_CPU0_P2_TX_BUF_C_DP<10>";
28"P5E_CPU0_P3_TX_BUF_C_DP<10>";
29"P5E_CPU0_P2_TX_BUF_C_DN<10>";
30"P5E_CPU0_P3_RX_BUF_DN<10>";
31"P5E_CPU0_P2_RX_BUF_DP<12>";
32"P5E_CPU0_P2_RX_BUF_DN<12>";
33"RST_SWB_BIC_BUF_N";
34"P5E_CPU0_P3_TX_BUF_C_DP<13>";
35"P5E_CPU0_P3_RX_BUF_DP<13>";
36"P5E_CPU0_P2_TX_BUF_C_DP<14>";
37"P5E_CPU0_P2_TX_BUF_C_DN<14>";
38"P5E_CPU0_P3_RX_BUF_DP<14>";
39"P5E_CPU0_P3_RX_BUF_DN<14>";
40"GND\g";
41"P5E_CPU0_P3_RX_BUF_DP<11>";
42"P5E_CPU0_P2_TX_BUF_C_DN<11>";
43"P5E_CPU0_P3_RX_BUF_DN<11>";
44"P5E_CPU0_P3_RX_BUF_DN<12>";
45"GPU_3V3IO_RSVD3";
46"P5E_CPU0_P2_TX_BUF_C_DP<13>";
47"P5E_CPU0_P3_RX_BUF_DN<13>";
48"P5E_CPU0_P2_RX_BUF_DP<13>";
49"P5E_CPU0_P2_RX_BUF_DN<13>";
50"P5E_CPU0_P3_TX_BUF_C_DP<14>";
51"P5E_CPU0_P3_TX_BUF_C_DN<14>";
52"P5E_CPU0_P2_RX_BUF_DP<14>";
53"P5E_CPU0_P2_RX_BUF_DN<14>";
54"GPU_3V3IO_RSVD1";
55"RST_BMC_FROM_SWB_N";
56"P5E_CPU0_P3_TX_BUF_C_DN<15>";
57"P5E_CPU0_P2_TX_BUF_C_DP<15>";
58"P5E_CPU0_P3_TX_BUF_C_DP<15>";
59"P5E_CPU0_P3_RX_BUF_DP<15>";
60"P5E_CPU0_P3_RX_BUF_DN<15>";
61"P5E_CPU0_P2_TX_BUF_C_DN<15>";
62"P5E_CPU0_P3_TX_BUF_C_DN<13>";
63"P5E_CPU0_P3_TX_BUF_C_DP<12>";
64"P5E_CPU0_P3_TX_BUF_C_DN<12>";
65"P5E_CPU0_P2_TX_BUF_C_DP<12>";
66"P5E_CPU0_P3_RX_BUF_DP<12>";
67"P5E_CPU0_P2_TX_BUF_C_DN<13>";
68"P5E_CPU0_P2_RX_BUF_DP<15>";
69"P5E_CPU0_P2_RX_BUF_DN<15>";
70"P5E_CPU0_P2_RX_BUF_DP<9>";
71"P5E_CPU0_P2_RX_BUF_DN<9>";
72"P5E_CPU0_P2_RX_BUF_DN<11>";
73"P5E_CPU0_P2_RX_BUF_DP<11>";
74"P5E_CPU0_P2_TX_BUF_C_DN<12>";
%"UNIVERSAL_GND"
"1","(-25,-250)","0","pure_quanta_power","I19";
;
CDS_LIB"pure_quanta_power"
HDL_POWER"GND";
"A"40;
%"UNIVERSAL_GND"
"1","(4850,-300)","0","pure_quanta_power","I74";
;
CDS_LIB"pure_quanta_power"
HDL_POWER"GND";
"A"4;
%"CONN112_10137002101LF"
"2","(6000,1650)","0","pure_quanta","I75";
;
LOCATION"J105"
$SEC"2"
CDS_SEC"2"
PART_TYPE"THLF"
MATERIAL"IO"
NEEDS_NO_SIZE"TRUE"
VALUE"CONN112_10137002-101LF"
CDS_LMAN_SYM_OUTLINE"-775,1650,775,-1650"
CDS_LIB"pure_quanta"
PART_NUMBER"DFHSB2FR012";
"N4"
$PN"N4"1;
"M4"
$PN"M4"4;
"N3"
$PN"N3"4;
"M3"
$PN"M3"28;
"N2"
$PN"N2"24;
"M2"
$PN"M2"4;
"N1"
$PN"N1"4;
"M1"
$PN"M1"10;
"L1"
$PN"L1"11;
"L2"
$PN"L2"23;
"L3"
$PN"L3"26;
"L4"
$PN"L4"5;
"K1"
$PN"K1"4;
"K2"
$PN"K2"25;
"K3"
$PN"K3"4;
"K4"
$PN"K4"6;
"J1"
$PN"J1"12;
"J2"
$PN"J2"4;
"J3"
$PN"J3"27;
"J4"
$PN"J4"4;
"I1"
$PN"I1"13;
"I2"
$PN"I2"22;
"I3"
$PN"I3"29;
"I4"
$PN"I4"7;
"H1"
$PN"H1"4;
"H2"
$PN"H2"21;
"H3"
$PN"H3"4;
"H4"
$PN"H4"42;
"G1"
$PN"G1"14;
"G2"
$PN"G2"4;
"G3"
$PN"G3"9;
"G4"
$PN"G4"4;
"F1"
$PN"F1"15;
"F2"
$PN"F2"20;
"F3"
$PN"F3"30;
"F4"
$PN"F4"41;
"E1"
$PN"E1"4;
"E2"
$PN"E2"19;
"E3"
$PN"E3"4;
"E4"
$PN"E4"43;
"D1"
$PN"D1"16;
"D2"
$PN"D2"4;
"D3"
$PN"D3"8;
"D4"
$PN"D4"4;
"C1"
$PN"C1"17;
"C2"
$PN"C2"70;
"C3"
$PN"C3"3;
"C4"
$PN"C4"73;
"B1"
$PN"B1"4;
"B2"
$PN"B2"71;
"B3"
$PN"B3"4;
"B4"
$PN"B4"72;
"A1"
$PN"A1"18;
"A2"
$PN"A2"4;
"A3"
$PN"A3"2;
"A4"
$PN"A4"4;
%"CONN112_10137002101LF"
"1","(1075,1650)","0","pure_quanta","I76";
;
LOCATION"J105"
$SEC"1"
CDS_SEC"1"
MATERIAL"IO"
PART_TYPE"THLF"
VALUE"CONN112_10137002-101LF"
NEEDS_NO_SIZE"TRUE"
CDS_LMAN_SYM_OUTLINE"-775,1650,775,-1650"
CDS_LIB"pure_quanta"
PART_NUMBER"DFHSB2FR012";
"N8"
$PN"N8"55;
"M8"
$PN"M8"40;
"N7"
$PN"N7"40;
"M7"
$PN"M7"50;
"N6"
$PN"N6"33;
"M6"
$PN"M6"40;
"N5"
$PN"N5"40;
"M5"
$PN"M5"63;
"L5"
$PN"L5"64;
"L6"
$PN"L6"34;
"L7"
$PN"L7"51;
"L8"
$PN"L8"58;
"K5"
$PN"K5"40;
"K6"
$PN"K6"62;
"K7"
$PN"K7"40;
"K8"
$PN"K8"56;
"J5"
$PN"J5"65;
"J6"
$PN"J6"40;
"J7"
$PN"J7"36;
"J8"
$PN"J8"40;
"I5"
$PN"I5"74;
"I6"
$PN"I6"46;
"I7"
$PN"I7"37;
"I8"
$PN"I8"57;
"H5"
$PN"H5"40;
"H6"
$PN"H6"67;
"H7"
$PN"H7"40;
"H8"
$PN"H8"61;
"G5"
$PN"G5"66;
"G6"
$PN"G6"40;
"G7"
$PN"G7"38;
"G8"
$PN"G8"40;
"F5"
$PN"F5"44;
"F6"
$PN"F6"35;
"F7"
$PN"F7"39;
"F8"
$PN"F8"59;
"E5"
$PN"E5"40;
"E6"
$PN"E6"47;
"E7"
$PN"E7"40;
"E8"
$PN"E8"60;
"D5"
$PN"D5"31;
"D6"
$PN"D6"40;
"D7"
$PN"D7"52;
"D8"
$PN"D8"40;
"C5"
$PN"C5"32;
"C6"
$PN"C6"48;
"C7"
$PN"C7"53;
"C8"
$PN"C8"68;
"B5"
$PN"B5"40;
"B6"
$PN"B6"49;
"B7"
$PN"B7"40;
"B8"
$PN"B8"69;
"A5"
$PN"A5"45;
"A6"
$PN"A6"40;
"A7"
$PN"A7"54;
"A8"
$PN"A8"40;
END.
